(kicad_pcb
	(version 20241229)
	(generator "pcbnew")
	(generator_version "9.0")
	(general
		(thickness 1.6642)
		(legacy_teardrops no)
	)
	(paper "A3")
	(title_block
		(title "PolarFire SoM")
		(date "2025-07-22")
		(rev "1.1.4")
		(company "Antmicro Ltd")
		(comment 1 "www.antmicro.com")
		(comment 9 "footprints 53-56 of 470")
	)
	(layers
		(0 "F.Cu" mixed)
		(4 "In1.Cu" power)
		(6 "In2.Cu" signal)
		(8 "In3.Cu" power)
		(10 "In4.Cu" signal)
		(12 "In5.Cu" power)
		(14 "In6.Cu" power)
		(16 "In7.Cu" signal)
		(18 "In8.Cu" power)
		(20 "In9.Cu" signal)
		(22 "In10.Cu" power)
		(24 "In11.Cu" signal)
		(26 "In12.Cu" signal)
		(2 "B.Cu" mixed)
		(9 "F.Adhes" user "F.Adhesive")
		(11 "B.Adhes" user "B.Adhesive")
		(13 "F.Paste" user)
		(15 "B.Paste" user)
		(5 "F.SilkS" user "F.Silkscreen")
		(7 "B.SilkS" user "B.Silkscreen")
		(1 "F.Mask" user)
		(3 "B.Mask" user)
		(17 "Dwgs.User" user "User.Drawings")
		(19 "Cmts.User" user "User.Comments")
		(21 "Eco1.User" user "User.Eco1")
		(23 "Eco2.User" user "User.Eco2")
		(25 "Edge.Cuts" user)
		(27 "Margin" user)
		(31 "F.CrtYd" user "F.Courtyard")
		(29 "B.CrtYd" user "B.Courtyard")
		(35 "F.Fab" user)
		(33 "B.Fab" user)
	)
	(footprint "antmicro-footprints:XSON-8_1x1.95mm_P0.5mm"
		(layer "F.Cu")
		(at 222.35 120.15)
		(property "Reference" "U19"
			(at -0.74 1.16 90)
			(layer "F.SilkS")
			(effects
				(font
					(size 0.7 0.7)
					(thickness 0.15)
				)
				(justify left bottom)
			)
		)
		(property "Value" "NTS0102_XSON"
			(at 0 2.2 0)
			(layer "F.Fab")
			(hide yes)
			(effects
				(font
					(size 0.7 0.7)
					(thickness 0.15)
				)
				(justify left bottom)
			)
		)
		(property "Datasheet" "http://www.farnell.com/datasheets/1760723.pdf"
			(at 0 0 0)
			(layer "F.Fab")
			(hide yes)
			(effects
				(font
					(size 1.27 1.27)
					(thickness 0.15)
				)
			)
		)
		(property "Description" "Transceiver, 1.65 V to 3.6 V, XSON-8"
			(at 0 0 0)
			(layer "F.Fab")
			(hide yes)
			(effects
				(font
					(size 1.27 1.27)
					(thickness 0.15)
				)
			)
		)
		(property "Author" "Antmicro"
			(at 0 0 0)
			(layer "F.Fab")
			(hide yes)
			(effects
				(font
					(size 1 1)
					(thickness 0.15)
				)
			)
		)
		(property "License" "Apache-2.0"
			(at 0 0 0)
			(layer "F.Fab")
			(hide yes)
			(effects
				(font
					(size 1 1)
					(thickness 0.15)
				)
			)
		)
		(property "MPN" "NTS0102GT"
			(at 0 0 0)
			(layer "F.Fab")
			(hide yes)
			(effects
				(font
					(size 1 1)
					(thickness 0.15)
				)
			)
		)
		(property "Manufacturer" "NXP"
			(at 0 0 0)
			(layer "F.Fab")
			(hide yes)
			(effects
				(font
					(size 1 1)
					(thickness 0.15)
				)
			)
		)
		(sheetname "/FPGA GPIO/")
		(sheetfile "fpga-gpio.kicad_sch")
		(attr smd)
		(fp_line
			(start -0.5 -1.1)
			(end 0.5 -1.1)
			(stroke
				(width 0.15)
				(type solid)
			)
			(layer "F.SilkS")
		)
		(fp_line
			(start 0.5 1.1)
			(end -0.5 1.1)
			(stroke
				(width 0.15)
				(type solid)
			)
			(layer "F.SilkS")
		)
		(fp_circle
			(center -0.75 -1.1)
			(end -0.701 -1.1)
			(stroke
				(width 0.15)
				(type solid)
			)
			(fill no)
			(layer "F.SilkS")
		)
		(fp_rect
			(start -0.8 -1.2)
			(end 0.8 1.2)
			(stroke
				(width 0.05)
				(type solid)
			)
			(fill no)
			(layer "F.CrtYd")
		)
		(fp_line
			(start -0.5305 -1.001)
			(end 0.5305 -1.001)
			(stroke
				(width 0.15)
				(type solid)
			)
			(layer "F.Fab")
		)
		(fp_line
			(start -0.5305 1)
			(end -0.5305 -1.001)
			(stroke
				(width 0.15)
				(type solid)
			)
			(layer "F.Fab")
		)
		(fp_line
			(start 0.5305 -1.001)
			(end 0.5305 1)
			(stroke
				(width 0.15)
				(type solid)
			)
			(layer "F.Fab")
		)
		(fp_line
			(start 0.5305 1)
			(end -0.5305 1)
			(stroke
				(width 0.15)
				(type solid)
			)
			(layer "F.Fab")
		)
		(fp_text user "${REFERENCE}"
			(at -0.527 5.905 0)
			(layer "F.Fab")
			(effects
				(font
					(size 0.7 0.7)
					(thickness 0.15)
				)
				(justify left bottom)
			)
		)
		(fp_text user "Author: Antmicro"
			(at -0.527 7.105 0)
			(layer "F.Fab")
			(effects
				(font
					(size 0.7 0.7)
					(thickness 0.15)
				)
				(justify left bottom)
			)
		)
		(fp_text user "License: Apache-2.0"
			(at -0.527 8.306 0)
			(layer "F.Fab")
			(effects
				(font
					(size 0.7 0.7)
					(thickness 0.15)
				)
				(justify left bottom)
			)
		)
		(pad "1" smd roundrect
			(at -0.45 -0.75 180)
			(size 0.6 0.3)
			(layers "F.Cu" "F.Mask" "F.Paste")
			(roundrect_rratio 0.25)
			(net 343 "/Ethernet/ETH.MDIO")
			(pinfunction "B_{2}")
			(pintype "bidirectional")
		)
		(pad "2" smd roundrect
			(at -0.45 -0.25 180)
			(size 0.6 0.25)
			(layers "F.Cu" "F.Mask" "F.Paste")
			(roundrect_rratio 0.25)
			(net 417 "GND")
			(pinfunction "GND")
			(pintype "power_in")
		)
		(pad "3" smd roundrect
			(at -0.45 0.25 180)
			(size 0.6 0.25)
			(layers "F.Cu" "F.Mask" "F.Paste")
			(roundrect_rratio 0.25)
			(net 649 "VDD")
			(pinfunction "VCC_{A}")
			(pintype "power_in")
		)
		(pad "4" smd roundrect
			(at -0.45 0.75 180)
			(size 0.6 0.3)
			(layers "F.Cu" "F.Mask" "F.Paste")
			(roundrect_rratio 0.25)
			(net 349 "/FPGA GPIO/PF_ETH_MDIO")
			(pinfunction "A_{2}")
			(pintype "bidirectional")
		)
		(pad "5" smd roundrect
			(at 0.45 0.75 180)
			(size 0.6 0.3)
			(layers "F.Cu" "F.Mask" "F.Paste")
			(roundrect_rratio 0.25)
			(net 344 "/FPGA GPIO/PF_ETH_MDC")
			(pinfunction "A_{1}")
			(pintype "bidirectional")
		)
		(pad "6" smd roundrect
			(at 0.45 0.25 180)
			(size 0.6 0.25)
			(layers "F.Cu" "F.Mask" "F.Paste")
			(roundrect_rratio 0.25)
			(net 649 "VDD")
			(pinfunction "OE")
			(pintype "input")
		)
		(pad "7" smd roundrect
			(at 0.45 -0.25 180)
			(size 0.6 0.25)
			(layers "F.Cu" "F.Mask" "F.Paste")
			(roundrect_rratio 0.25)
			(net 50 "+3V3")
			(pinfunction "VCC_{B}")
			(pintype "power_in")
		)
		(pad "8" smd roundrect
			(at 0.45 -0.75 180)
			(size 0.6 0.3)
			(layers "F.Cu" "F.Mask" "F.Paste")
			(roundrect_rratio 0.25)
			(net 618 "/Ethernet/ETH.MDC")
			(pinfunction "B_{1}")
			(pintype "bidirectional")
		)
	)
	(footprint "antmicro-footprints:R_0402_1005Metric"
		(layer "F.Cu")
		(at 179.55 138.3175 -90)
		(descr "Resistor SMD 0402")
		(tags "resistor SMD 0402")
		(property "Reference" "R11"
			(at -3.1775 -8 180)
			(layer "F.SilkS")
			(effects
				(font
					(size 0.7 0.7)
					(thickness 0.15)
				)
				(justify right bottom)
			)
		)
		(property "Value" "R_4R7_0402"
			(at -1.011843 1.772047 90)
			(layer "F.Fab")
			(hide yes)
			(effects
				(font
					(size 0.7 0.7)
					(thickness 0.15)
				)
				(justify right bottom)
			)
		)
		(property "Datasheet" "https://www.bourns.com/docs/product-datasheets/cr.pdf"
			(at 0 0 270)
			(layer "F.Fab")
			(hide yes)
			(effects
				(font
					(size 1.27 1.27)
					(thickness 0.15)
				)
			)
		)
		(property "Description" "SMD Chip Resistor, 4.7 ohm, ± 1%, 62.5 mW, 0402 [1005 Metric], Thick Film, General Purpose"
			(at 0 0 270)
			(layer "F.Fab")
			(hide yes)
			(effects
				(font
					(size 1.27 1.27)
					(thickness 0.15)
				)
			)
		)
		(property "Author" "Antmicro"
			(at 41.2325 317.8675 0)
			(layer "F.Fab")
			(hide yes)
			(effects
				(font
					(size 1 1)
					(thickness 0.15)
				)
			)
		)
		(property "License" "Apache-2.0"
			(at 41.2325 317.8675 0)
			(layer "F.Fab")
			(hide yes)
			(effects
				(font
					(size 1 1)
					(thickness 0.15)
				)
			)
		)
		(property "MPN" "CR0402-FX-4R70GLF"
			(at 41.2325 317.8675 0)
			(layer "F.Fab")
			(hide yes)
			(effects
				(font
					(size 1 1)
					(thickness 0.15)
				)
			)
		)
		(property "Manufacturer" "Bourns"
			(at 41.2325 317.8675 0)
			(layer "F.Fab")
			(hide yes)
			(effects
				(font
					(size 1 1)
					(thickness 0.15)
				)
			)
		)
		(property "Public" ""
			(at 41.2325 317.8675 0)
			(layer "F.Fab")
			(hide yes)
			(effects
				(font
					(size 1 1)
					(thickness 0.15)
				)
			)
		)
		(property "Tolerance" "1%"
			(at 41.2325 317.8675 0)
			(layer "F.Fab")
			(hide yes)
			(effects
				(font
					(size 1 1)
					(thickness 0.15)
				)
			)
		)
		(property "Val" "4R7"
			(at 41.2325 317.8675 0)
			(layer "F.Fab")
			(hide yes)
			(effects
				(font
					(size 1 1)
					(thickness 0.15)
				)
			)
		)
		(sheetname "/Supply/")
		(sheetfile "supply.kicad_sch")
		(attr smd)
		(fp_rect
			(start -0.925 -0.47)
			(end 0.925 0.47)
			(stroke
				(width 0.05)
				(type default)
			)
			(fill no)
			(layer "F.CrtYd")
		)
		(fp_rect
			(start -0.5 -0.25)
			(end 0.5 0.25)
			(stroke
				(width 0.15)
				(type solid)
			)
			(fill no)
			(layer "F.Fab")
		)
		(fp_text user "${REFERENCE}"
			(at -0.95 3.168 270)
			(layer "F.Fab")
			(effects
				(font
					(size 0.7 0.7)
					(thickness 0.15)
				)
				(justify left bottom)
			)
		)
		(fp_text user "Author: Antmicro"
			(at -0.95 4.169 270)
			(layer "F.Fab")
			(effects
				(font
					(size 0.7 0.7)
					(thickness 0.15)
				)
				(justify left bottom)
			)
		)
		(fp_text user "License: Apache-2.0"
			(at -0.95 5.169 270)
			(layer "F.Fab")
			(effects
				(font
					(size 0.7 0.7)
					(thickness 0.15)
				)
				(justify left bottom)
			)
		)
		(pad "1" smd roundrect
			(at -0.48 0 270)
			(size 0.59 0.64)
			(layers "F.Cu" "F.Mask" "F.Paste")
			(roundrect_rratio 0.25)
			(net 90 "+5V")
			(pintype "passive")
		)
		(pad "2" smd roundrect
			(at 0.48 0 270)
			(size 0.59 0.64)
			(layers "F.Cu" "F.Mask" "F.Paste")
			(roundrect_rratio 0.25)
			(net 3 "Net-(U7-AVIN)")
			(pintype "passive")
		)
	)
	(footprint "antmicro-footprints:R_0402_1005Metric"
		(layer "F.Cu")
		(at 183.1 121.45)
		(descr "Resistor SMD 0402")
		(tags "resistor SMD 0402")
		(property "Reference" "R91"
			(at 3.14 4.58 90)
			(layer "F.SilkS")
			(effects
				(font
					(size 0.7 0.7)
					(thickness 0.15)
				)
				(justify left bottom)
			)
		)
		(property "Value" "R_0R_0402"
			(at -1.011843 1.772047 0)
			(layer "F.Fab")
			(hide yes)
			(effects
				(font
					(size 0.7 0.7)
					(thickness 0.15)
				)
				(justify left bottom)
			)
		)
		(property "Datasheet" "https://industrial.panasonic.com/cdbs/www-data/pdf/RDA0000/AOA0000C301.pdf"
			(at 0 0 0)
			(layer "F.Fab")
			(hide yes)
			(effects
				(font
					(size 1.27 1.27)
					(thickness 0.15)
				)
			)
		)
		(property "Description" "SMD Chip Resistor, Jumper, 0 ohm, 100 mW, 0402 [1005 Metric], Thick Film, General Purpose"
			(at 0 0 0)
			(layer "F.Fab")
			(hide yes)
			(effects
				(font
					(size 1.27 1.27)
					(thickness 0.15)
				)
			)
		)
		(property "Author" "Antmicro"
			(at 0 0 0)
			(layer "F.Fab")
			(hide yes)
			(effects
				(font
					(size 1 1)
					(thickness 0.15)
				)
			)
		)
		(property "Current" "1A"
			(at 0 0 0)
			(layer "F.Fab")
			(hide yes)
			(effects
				(font
					(size 1 1)
					(thickness 0.15)
				)
			)
		)
		(property "DNP" "DNP"
			(at 0 0 0)
			(layer "F.Fab")
			(hide yes)
			(effects
				(font
					(size 1 1)
					(thickness 0.15)
				)
			)
		)
		(property "License" "Apache-2.0"
			(at 0 0 0)
			(layer "F.Fab")
			(hide yes)
			(effects
				(font
					(size 1 1)
					(thickness 0.15)
				)
			)
		)
		(property "MPN" "ERJ2GE0R00X"
			(at 0 0 0)
			(layer "F.Fab")
			(hide yes)
			(effects
				(font
					(size 1 1)
					(thickness 0.15)
				)
			)
		)
		(property "Manufacturer" "Panasonic"
			(at 0 0 0)
			(layer "F.Fab")
			(hide yes)
			(effects
				(font
					(size 1 1)
					(thickness 0.15)
				)
			)
		)
		(property "Public" ""
			(at 0 0 0)
			(layer "F.Fab")
			(hide yes)
			(effects
				(font
					(size 1 1)
					(thickness 0.15)
				)
			)
		)
		(property "Tolerance" "~"
			(at 0 0 0)
			(layer "F.Fab")
			(hide yes)
			(effects
				(font
					(size 1 1)
					(thickness 0.15)
				)
			)
		)
		(property "Val" "0R"
			(at 0 0 0)
			(layer "F.Fab")
			(hide yes)
			(effects
				(font
					(size 1 1)
					(thickness 0.15)
				)
			)
		)
		(sheetname "/FPGA Config/")
		(sheetfile "fpga-config.kicad_sch")
		(attr smd)
		(fp_rect
			(start -0.925 -0.47)
			(end 0.925 0.47)
			(stroke
				(width 0.05)
				(type default)
			)
			(fill no)
			(layer "F.CrtYd")
		)
		(fp_rect
			(start -0.5 -0.25)
			(end 0.5 0.25)
			(stroke
				(width 0.15)
				(type solid)
			)
			(fill no)
			(layer "F.Fab")
		)
		(fp_text user "Author: Antmicro"
			(at -0.95 4.169 0)
			(layer "F.Fab")
			(effects
				(font
					(size 0.7 0.7)
					(thickness 0.15)
				)
				(justify left bottom)
			)
		)
		(fp_text user "${REFERENCE}"
			(at -0.95 3.168 0)
			(layer "F.Fab")
			(effects
				(font
					(size 0.7 0.7)
					(thickness 0.15)
				)
				(justify left bottom)
			)
		)
		(fp_text user "License: Apache-2.0"
			(at -0.95 5.169 0)
			(layer "F.Fab")
			(effects
				(font
					(size 0.7 0.7)
					(thickness 0.15)
				)
				(justify left bottom)
			)
		)
		(pad "1" smd roundrect
			(at -0.48 0)
			(size 0.59 0.64)
			(layers "F.Cu" "F.Mask" "F.Paste")
			(roundrect_rratio 0.25)
			(net 125 "JTAG_TDO")
			(pintype "passive")
		)
		(pad "2" smd roundrect
			(at 0.48 0)
			(size 0.59 0.64)
			(layers "F.Cu" "F.Mask" "F.Paste")
			(roundrect_rratio 0.25)
			(net 189 "Net-(U1D-TDO)")
			(pintype "passive")
		)
	)
	(footprint "antmicro-footprints:FB_0402_1005Metric"
		(layer "F.Cu")
		(at 208.085 145.8)
		(descr "Ferrite Bead SMD 0402")
		(tags "ferrite bead SMD 0402")
		(property "Reference" "FB6"
			(at -6.135 8.515 90)
			(layer "F.SilkS")
			(effects
				(font
					(size 0.7 0.7)
					(thickness 0.15)
				)
				(justify left bottom)
			)
		)
		(property "Value" "FB_120Z_1.2A_TDK-MPZ_0402"
			(at 0 1.4 0)
			(layer "F.Fab")
			(hide yes)
			(effects
				(font
					(size 0.7 0.7)
					(thickness 0.15)
				)
				(justify left bottom)
			)
		)
		(property "Datasheet" "https://product.tdk.com/en/search/emc/emc/beads/info?part_no=MPZ1005S121CT000"
			(at 0 0 0)
			(layer "F.Fab")
			(hide yes)
			(effects
				(font
					(size 1.27 1.27)
					(thickness 0.15)
				)
			)
		)
		(property "Description" "Ferrite Bead, 0402 [1005 Metric], 120 ohm, 1.2A, MPZ, 0.06 ohm, ± 25%, DC Power line"
			(at 0 0 0)
			(layer "F.Fab")
			(hide yes)
			(effects
				(font
					(size 1.27 1.27)
					(thickness 0.15)
				)
			)
		)
		(property "Author" "Antmicro"
			(at 0 0 0)
			(layer "F.Fab")
			(hide yes)
			(effects
				(font
					(size 1 1)
					(thickness 0.15)
				)
			)
		)
		(property "Current" ""
			(at 0 0 0)
			(layer "F.Fab")
			(hide yes)
			(effects
				(font
					(size 1 1)
					(thickness 0.15)
				)
			)
		)
		(property "License" "Apache-2.0"
			(at 0 0 0)
			(layer "F.Fab")
			(hide yes)
			(effects
				(font
					(size 1 1)
					(thickness 0.15)
				)
			)
		)
		(property "MPN" "MPZ1005S121CT000"
			(at 0 0 0)
			(layer "F.Fab")
			(hide yes)
			(effects
				(font
					(size 1 1)
					(thickness 0.15)
				)
			)
		)
		(property "Manufacturer" "TDK"
			(at 0 0 0)
			(layer "F.Fab")
			(hide yes)
			(effects
				(font
					(size 1 1)
					(thickness 0.15)
				)
			)
		)
		(property "Public" ""
			(at 0 0 0)
			(layer "F.Fab")
			(hide yes)
			(effects
				(font
					(size 1 1)
					(thickness 0.15)
				)
			)
		)
		(property "Val" "120Z/1.2A"
			(at 0 0 0)
			(layer "F.Fab")
			(hide yes)
			(effects
				(font
					(size 1 1)
					(thickness 0.15)
				)
			)
		)
		(sheetname "/MIPI CrossLink/")
		(sheetfile "crosslink.kicad_sch")
		(attr smd)
		(fp_rect
			(start -0.925 -0.47)
			(end 0.925 0.47)
			(stroke
				(width 0.05)
				(type default)
			)
			(fill no)
			(layer "F.CrtYd")
		)
		(fp_rect
			(start -0.5 -0.25)
			(end 0.5 0.25)
			(stroke
				(width 0.15)
				(type solid)
			)
			(fill no)
			(layer "F.Fab")
		)
		(fp_text user "Author: Antmicro"
			(at -0.95 4.169 0)
			(layer "F.Fab")
			(effects
				(font
					(size 0.7 0.7)
					(thickness 0.15)
				)
				(justify left bottom)
			)
		)
		(fp_text user "${REFERENCE}"
			(at -0.95 3.168 0)
			(layer "F.Fab")
			(effects
				(font
					(size 0.7 0.7)
					(thickness 0.15)
				)
				(justify left bottom)
			)
		)
		(fp_text user "License: Apache-2.0"
			(at -0.95 5.169 0)
			(layer "F.Fab")
			(effects
				(font
					(size 0.7 0.7)
					(thickness 0.15)
				)
				(justify left bottom)
			)
		)
		(pad "1" smd roundrect
			(at -0.48 0)
			(size 0.59 0.64)
			(layers "F.Cu" "F.Mask" "F.Paste")
			(roundrect_rratio 0.25)
			(net 185 "/MIPI CrossLink/CL_VCCIO1")
			(pintype "passive")
		)
		(pad "2" smd roundrect
			(at 0.48 0)
			(size 0.59 0.64)
			(layers "F.Cu" "F.Mask" "F.Paste")
			(roundrect_rratio 0.25)
			(net 237 "1V8_CL")
			(pintype "passive")
		)
	)
)
